# T6G (Grand Teton) — schematic netlist excerpt (pin names and nets, part order shuffled) for the footprints in the layout excerpt that follows; sources: Cadence DE-HDL packaged netlist, KiCad conversion of 04192023_DAF0TMB3IC0_F0TG_MB_C_brd_V02_OCP.brd

PC496  Q_CAPP  220UF 4V 20% SPCAP  pkg SMLF  page 194 : A = PVDDCR_CPU0_P0 ; B = GND
C2371  Q_CAP  22UF 4V 20% X6S  pkg C0402  page 73 : A = PVDDCR_CPU1_P1 ; B = GND

(kicad_pcb
	(version 20260206)
	(generator "pcbnew")
	(generator_version "10.0")
	(general
		(thickness 1.6)
		(legacy_teardrops no)
	)
	(paper "A4")
	(title_block
		(title "04192023_DAF0TMB3IC0_F0TG_MB_C_brd_V02_OCP.brd")
		(comment 1 "Grand Teton / footprints 8351-8352 of 8354")
	)
	(layers
		(0 "F.Cu" signal "TOP")
		(4 "In1.Cu" signal "GND")
		(6 "In2.Cu" signal "IN1")
		(8 "In3.Cu" signal "GND1")
		(10 "In4.Cu" signal "IN2")
		(12 "In5.Cu" signal "GND2")
		(14 "In6.Cu" signal "IN3")
		(16 "In7.Cu" signal "GND3")
		(18 "In8.Cu" signal "VCC")
		(20 "In9.Cu" signal "VCC1")
		(22 "In10.Cu" signal "GND4")
		(24 "In11.Cu" signal "IN4")
		(26 "In12.Cu" signal "GND5")
		(28 "In13.Cu" signal "IN5")
		(30 "In14.Cu" signal "GND6")
		(32 "In15.Cu" signal "IN6")
		(34 "In16.Cu" signal "GND7")
		(2 "B.Cu" signal "BOTTOM")
		(9 "F.Adhes" user "F.Adhesive")
		(11 "B.Adhes" user "B.Adhesive")
		(13 "F.Paste" user "Package Geometry/Pastemask Top")
		(15 "B.Paste" user "Package Geometry/Pastemask Bottom")
		(5 "F.SilkS" user "Ref Des/Silkscreen Top")
		(7 "B.SilkS" user "Ref Des/Silkscreen Bottom")
		(1 "F.Mask" user "Board Geometry/Soldermask Top")
		(3 "B.Mask" user "Board Geometry/Soldermask Bottom")
		(17 "Dwgs.User" user "User.Drawings")
		(19 "Cmts.User" user "User.Comments")
		(21 "Eco1.User" user "User.Eco1")
		(23 "Eco2.User" user "User.Eco2")
		(25 "Edge.Cuts" user "Board Geometry/Outline")
		(27 "Margin" user)
		(31 "F.CrtYd" user "Package Geometry/Place Bound Top")
		(29 "B.CrtYd" user "Package Geometry/Place Bound Bottom")
		(35 "F.Fab" user "Ref Des/Assembly Top")
		(33 "B.Fab" user "Ref Des/Assembly Bottom")
	)
	(footprint ""
		(layer "B.Cu")
		(at 115.384834 -271.395952 180)
		(property "Reference" "C2371"
			(at 0 0 0)
			(layer "B.SilkS")
			(hide yes)
			(effects
				(font
					(size 1.27 1.27)
				)
				(justify mirror)
			)
		)
		(property "Value" ""
			(at 0 0 0)
			(layer "B.Fab")
			(effects
				(font
					(size 1.27 1.27)
				)
				(justify mirror)
			)
		)
		(duplicate_pad_numbers_are_jumpers no)
		(fp_line
			(start 0.7874 0.4064)
			(end 0.7874 -0.4064)
			(stroke
				(width 0.1524)
				(type default)
			)
			(layer "B.SilkS")
		)
		(fp_line
			(start 0.7874 -0.4064)
			(end -0.7874 -0.4064)
			(stroke
				(width 0.1524)
				(type default)
			)
			(layer "B.SilkS")
		)
		(fp_line
			(start -0.7874 0.4064)
			(end 0.7874 0.4064)
			(stroke
				(width 0.1524)
				(type default)
			)
			(layer "B.SilkS")
		)
		(fp_line
			(start -0.7874 -0.4064)
			(end -0.7874 0.4064)
			(stroke
				(width 0.1524)
				(type default)
			)
			(layer "B.SilkS")
		)
		(fp_line
			(start 0.67945 0.3048)
			(end 0.67945 -0.305054)
			(stroke
				(width 0.1)
				(type default)
			)
			(layer "B.Fab")
		)
		(fp_line
			(start 0.67945 -0.305054)
			(end 0.12065 -0.305054)
			(stroke
				(width 0.1)
				(type default)
			)
			(layer "B.Fab")
		)
		(fp_line
			(start 0.12065 0.3048)
			(end 0.67945 0.3048)
			(stroke
				(width 0.1)
				(type default)
			)
			(layer "B.Fab")
		)
		(fp_line
			(start 0.12065 0.2794)
			(end 0.12065 0.3048)
			(stroke
				(width 0.1)
				(type default)
			)
			(layer "B.Fab")
		)
		(fp_line
			(start 0.12065 -0.2794)
			(end -0.12065 -0.2794)
			(stroke
				(width 0.1)
				(type default)
			)
			(layer "B.Fab")
		)
		(fp_line
			(start 0.12065 -0.305054)
			(end 0.12065 -0.2794)
			(stroke
				(width 0.1)
				(type default)
			)
			(layer "B.Fab")
		)
		(fp_line
			(start -0.120396 0.3048)
			(end -0.120396 0.2794)
			(stroke
				(width 0.1)
				(type default)
			)
			(layer "B.Fab")
		)
		(fp_line
			(start -0.120396 0.2794)
			(end 0.12065 0.2794)
			(stroke
				(width 0.1)
				(type default)
			)
			(layer "B.Fab")
		)
		(fp_line
			(start -0.12065 -0.2794)
			(end -0.12065 -0.3048)
			(stroke
				(width 0.1)
				(type default)
			)
			(layer "B.Fab")
		)
		(fp_line
			(start -0.12065 -0.3048)
			(end -0.67945 -0.3048)
			(stroke
				(width 0.1)
				(type default)
			)
			(layer "B.Fab")
		)
		(fp_line
			(start -0.67945 0.3048)
			(end -0.120396 0.3048)
			(stroke
				(width 0.1)
				(type default)
			)
			(layer "B.Fab")
		)
		(fp_line
			(start -0.67945 -0.3048)
			(end -0.67945 0.3048)
			(stroke
				(width 0.1)
				(type default)
			)
			(layer "B.Fab")
		)
		(pad "1" smd circle
			(at 0.40005 0)
			(size 0 0)
			(layers "B.Cu" "B.Mask" "B.Paste")
			(net "PVDDCR_CPU1_P1")
		)
		(pad "2" smd circle
			(at -0.40005 0)
			(size 0 0)
			(layers "B.Cu" "B.Mask" "B.Paste")
			(net "GND")
		)
	)
	(footprint ""
		(layer "B.Cu")
		(at 388.88162 -189.46495 90)
		(property "Reference" "PC496"
			(at 6.321044 0.761746 270)
			(unlocked yes)
			(layer "B.SilkS")
			(effects
				(font
					(size 0.7874 0.5842)
					(thickness 0.1524)
				)
				(justify left mirror)
			)
		)
		(property "Value" ""
			(at 0 0 90)
			(layer "B.Fab")
			(effects
				(font
					(size 1.27 1.27)
				)
				(justify mirror)
			)
		)
		(duplicate_pad_numbers_are_jumpers no)
		(fp_line
			(start 4.533392 -2.249932)
			(end -4.533392 -2.249932)
			(stroke
				(width 0.1524)
				(type default)
			)
			(layer "B.SilkS")
		)
		(fp_line
			(start -4.533392 -2.249932)
			(end -4.533392 2.249932)
			(stroke
				(width 0.1524)
				(type default)
			)
			(layer "B.SilkS")
		)
		(fp_line
			(start 4.533392 2.249932)
			(end 4.533392 -2.249932)
			(stroke
				(width 0.1524)
				(type default)
			)
			(layer "B.SilkS")
		)
		(fp_line
			(start -4.533392 2.249932)
			(end 4.533392 2.249932)
			(stroke
				(width 0.1524)
				(type default)
			)
			(layer "B.SilkS")
		)
		(fp_rect
			(start 4.533392 -2.326132)
			(end 5.39242 2.326132)
			(stroke
				(width 0)
				(type default)
			)
			(fill yes)
			(layer "B.SilkS")
		)
		(fp_line
			(start 3.750056 -2.249932)
			(end -3.750056 -2.249932)
			(stroke
				(width 0.1)
				(type default)
			)
			(layer "B.Fab")
		)
		(fp_line
			(start -3.750056 -2.249932)
			(end -3.750056 2.249932)
			(stroke
				(width 0.1)
				(type default)
			)
			(layer "B.Fab")
		)
		(fp_line
			(start 3.750056 2.249932)
			(end 3.750056 -2.249932)
			(stroke
				(width 0.1)
				(type default)
			)
			(layer "B.Fab")
		)
		(fp_line
			(start -3.750056 2.249932)
			(end 3.750056 2.249932)
			(stroke
				(width 0.1)
				(type default)
			)
			(layer "B.Fab")
		)
		(fp_text user "+"
			(at 6.322314 0.786384 0)
			(unlocked yes)
			(layer "B.SilkS")
			(effects
				(font
					(size 1.905 1.4224)
					(thickness 0.1524)
				)
				(justify left mirror)
			)
		)
		(fp_text user "-"
			(at -4.841748 0.861822 90)
			(unlocked yes)
			(layer "B.SilkS")
			(effects
				(font
					(size 1.905 1.4224)
					(thickness 0.1524)
				)
				(justify left mirror)
			)
		)
		(fp_text user "-"
			(at -4.8514 -0.14605 90)
			(unlocked yes)
			(layer "B.Fab")
			(effects
				(font
					(size 1.905 1.4224)
					(thickness 0.1524)
				)
				(justify left mirror)
			)
		)
		(fp_text user "+"
			(at 6.322314 0.786384 0)
			(unlocked yes)
			(layer "B.Fab")
			(effects
				(font
					(size 1.905 1.4224)
					(thickness 0.1524)
				)
				(justify left mirror)
			)
		)
		(pad "1" smd rect
			(at 3.199892 0 270)
			(size 2.413 2.8194)
			(layers "B.Cu" "B.Mask" "B.Paste")
			(net "PVDDCR_CPU0_P0")
		)
		(pad "2" smd rect
			(at -3.199892 0 270)
			(size 2.413 2.8194)
			(layers "B.Cu" "B.Mask" "B.Paste")
			(net "GND")
		)
	)
)
